# S9S_MB_2U (Grand Teton) — schematic netlist excerpt (pin names and nets, part order shuffled) for the footprints in the layout excerpt that follows; sources: Cadence DE-HDL packaged netlist, KiCad conversion of 03242023_DA0F0TMBIJ0_F0T_Motherboard_J_brd_V01_OCP.brd

R2939  Q_RES  33.2 1% CHIP  pkg 0402LF  page 213 : A = FM_GPU_HSC_EN_R ; B = FM_GPU_HSC_EN
C150  Q_CAP_DIFFBUS  DIFF BUS_0.22UF 6.3V 20% X6S  pkg C0201  page 178 : \1\ = DMI_CPU0_PCH_TX_C_DP<2> ; \2\ = DMI_CPU0_PCH_TX_DP<2>

(kicad_pcb
	(version 20260206)
	(generator "pcbnew")
	(generator_version "10.0")
	(general
		(thickness 1.6)
		(legacy_teardrops no)
	)
	(paper "A4")
	(title_block
		(title "03242023_DA0F0TMBIJ0_F0T_Motherboard_J_brd_V01_OCP.brd")
		(comment 1 "Grand Teton / footprints 2918-2919 of 6105")
	)
	(layers
		(0 "F.Cu" signal "TOP")
		(4 "In1.Cu" signal "GND")
		(6 "In2.Cu" signal "IN1")
		(8 "In3.Cu" signal "GND1")
		(10 "In4.Cu" signal "IN2")
		(12 "In5.Cu" signal "GND2")
		(14 "In6.Cu" signal "IN3")
		(16 "In7.Cu" signal "GND3")
		(18 "In8.Cu" signal "VCC")
		(20 "In9.Cu" signal "VCC1")
		(22 "In10.Cu" signal "GND4")
		(24 "In11.Cu" signal "IN4")
		(26 "In12.Cu" signal "GND5")
		(28 "In13.Cu" signal "IN5")
		(30 "In14.Cu" signal "GND6")
		(32 "In15.Cu" signal "IN6")
		(34 "In16.Cu" signal "GND7")
		(2 "B.Cu" signal "BOTTOM")
		(9 "F.Adhes" user "F.Adhesive")
		(11 "B.Adhes" user "B.Adhesive")
		(13 "F.Paste" user "Package Geometry/Pastemask Top")
		(15 "B.Paste" user "Package Geometry/Pastemask Bottom")
		(5 "F.SilkS" user "Ref Des/Silkscreen Top")
		(7 "B.SilkS" user "Ref Des/Silkscreen Bottom")
		(1 "F.Mask" user "Board Geometry/Soldermask Top")
		(3 "B.Mask" user "Board Geometry/Soldermask Bottom")
		(17 "Dwgs.User" user "User.Drawings")
		(19 "Cmts.User" user "User.Comments")
		(21 "Eco1.User" user "User.Eco1")
		(23 "Eco2.User" user "User.Eco2")
		(25 "Edge.Cuts" user "Board Geometry/Outline")
		(27 "Margin" user)
		(31 "F.CrtYd" user "Package Geometry/Place Bound Top")
		(29 "B.CrtYd" user "Package Geometry/Place Bound Bottom")
		(35 "F.Fab" user "Ref Des/Assembly Top")
		(33 "B.Fab" user "Ref Des/Assembly Bottom")
	)
	(footprint ""
		(layer "F.Cu")
		(at 164.64788 -107.025948 180)
		(property "Reference" "R2939"
			(at 0 0 180)
			(layer "F.SilkS")
			(hide yes)
			(effects
				(font
					(size 1.27 1.27)
				)
			)
		)
		(property "Value" ""
			(at 0 0 180)
			(layer "F.Fab")
			(effects
				(font
					(size 1.27 1.27)
				)
			)
		)
		(duplicate_pad_numbers_are_jumpers no)
		(fp_line
			(start 0.7874 0.4064)
			(end -0.7874 0.4064)
			(stroke
				(width 0.1524)
				(type default)
			)
			(layer "F.SilkS")
		)
		(fp_line
			(start 0.7874 -0.4064)
			(end 0.7874 0.4064)
			(stroke
				(width 0.1524)
				(type default)
			)
			(layer "F.SilkS")
		)
		(fp_line
			(start -0.7874 0.4064)
			(end -0.7874 -0.4064)
			(stroke
				(width 0.1524)
				(type default)
			)
			(layer "F.SilkS")
		)
		(fp_line
			(start -0.7874 -0.4064)
			(end 0.7874 -0.4064)
			(stroke
				(width 0.1524)
				(type default)
			)
			(layer "F.SilkS")
		)
		(fp_line
			(start 0.67945 0.3048)
			(end 0.120396 0.3048)
			(stroke
				(width 0.1)
				(type default)
			)
			(layer "F.Fab")
		)
		(fp_line
			(start 0.67945 -0.3048)
			(end 0.67945 0.3048)
			(stroke
				(width 0.1)
				(type default)
			)
			(layer "F.Fab")
		)
		(fp_line
			(start 0.12065 -0.2794)
			(end 0.12065 -0.3048)
			(stroke
				(width 0.1)
				(type default)
			)
			(layer "F.Fab")
		)
		(fp_line
			(start 0.12065 -0.3048)
			(end 0.67945 -0.3048)
			(stroke
				(width 0.1)
				(type default)
			)
			(layer "F.Fab")
		)
		(fp_line
			(start 0.120396 0.3048)
			(end 0.120396 0.2794)
			(stroke
				(width 0.1)
				(type default)
			)
			(layer "F.Fab")
		)
		(fp_line
			(start 0.120396 0.2794)
			(end -0.12065 0.2794)
			(stroke
				(width 0.1)
				(type default)
			)
			(layer "F.Fab")
		)
		(fp_line
			(start -0.12065 0.3048)
			(end -0.67945 0.3048)
			(stroke
				(width 0.1)
				(type default)
			)
			(layer "F.Fab")
		)
		(fp_line
			(start -0.12065 0.2794)
			(end -0.12065 0.3048)
			(stroke
				(width 0.1)
				(type default)
			)
			(layer "F.Fab")
		)
		(fp_line
			(start -0.12065 -0.2794)
			(end 0.12065 -0.2794)
			(stroke
				(width 0.1)
				(type default)
			)
			(layer "F.Fab")
		)
		(fp_line
			(start -0.12065 -0.305054)
			(end -0.12065 -0.2794)
			(stroke
				(width 0.1)
				(type default)
			)
			(layer "F.Fab")
		)
		(fp_line
			(start -0.67945 0.3048)
			(end -0.67945 -0.305054)
			(stroke
				(width 0.1)
				(type default)
			)
			(layer "F.Fab")
		)
		(fp_line
			(start -0.67945 -0.305054)
			(end -0.12065 -0.305054)
			(stroke
				(width 0.1)
				(type default)
			)
			(layer "F.Fab")
		)
		(pad "1" smd circle
			(at -0.40005 0 180)
			(size 0 0)
			(layers "F.Cu" "F.Mask" "F.Paste")
			(net "FM_GPU_HSC_EN_R")
		)
		(pad "2" smd circle
			(at 0.40005 0 180)
			(size 0 0)
			(layers "F.Cu" "F.Mask" "F.Paste")
			(net "FM_GPU_HSC_EN")
		)
	)
	(footprint ""
		(layer "F.Cu")
		(at 345.79179 -69.36994 90)
		(property "Reference" "C150"
			(at 0 0 90)
			(layer "F.SilkS")
			(hide yes)
			(effects
				(font
					(size 1.27 1.27)
				)
			)
		)
		(property "Value" ""
			(at 0 0 90)
			(layer "F.Fab")
			(effects
				(font
					(size 1.27 1.27)
				)
			)
		)
		(duplicate_pad_numbers_are_jumpers no)
		(fp_line
			(start 0.299974 -0.150114)
			(end 0.299974 0.150114)
			(stroke
				(width 0.1)
				(type default)
			)
			(layer "F.Fab")
		)
		(fp_line
			(start -0.299974 -0.150114)
			(end 0.299974 -0.150114)
			(stroke
				(width 0.1)
				(type default)
			)
			(layer "F.Fab")
		)
		(fp_line
			(start 0.299974 0.150114)
			(end -0.299974 0.150114)
			(stroke
				(width 0.1)
				(type default)
			)
			(layer "F.Fab")
		)
		(fp_line
			(start -0.299974 0.150114)
			(end -0.299974 -0.150114)
			(stroke
				(width 0.1)
				(type default)
			)
			(layer "F.Fab")
		)
		(pad "1" smd rect
			(at -0.2667 0 90)
			(size 0.3048 0.381)
			(layers "F.Cu" "F.Mask" "F.Paste")
			(net "DMI_CPU0_PCH_TX_C_DP<2>")
		)
		(pad "2" smd rect
			(at 0.2667 0 90)
			(size 0.3048 0.381)
			(layers "F.Cu" "F.Mask" "F.Paste")
			(net "DMI_CPU0_PCH_TX_DP<2>")
		)
	)
)
